(kicad_pcb
	(version 20260206)
	(generator "pcbnew")
	(generator_version "10.0")
	(general
		(thickness 1.6)
		(legacy_teardrops no)
	)
	(paper "A4")
	(title_block
		(title "Wiwynn_Tioga_Pass_MB.brd")
		(comment 1 "Tioga Pass / footprints 3202-3208 of 4770")
	)
	(layers
		(0 "F.Cu" signal "TOP")
		(4 "In1.Cu" signal "L2GND")
		(6 "In2.Cu" signal "L3")
		(8 "In3.Cu" signal "L4GND")
		(10 "In4.Cu" signal "L5")
		(12 "In5.Cu" signal "L6GND")
		(14 "In6.Cu" signal "L7VCC")
		(16 "In7.Cu" signal "L8VCC")
		(18 "In8.Cu" signal "L9GND")
		(20 "In9.Cu" signal "L10")
		(22 "In10.Cu" signal "L11GND")
		(24 "In11.Cu" signal "L12")
		(26 "In12.Cu" signal "L13GND")
		(2 "B.Cu" signal "BOTTOM")
		(9 "F.Adhes" user "F.Adhesive")
		(11 "B.Adhes" user "B.Adhesive")
		(13 "F.Paste" user "Package Geometry/Pastemask Top")
		(15 "B.Paste" user "Package Geometry/Pastemask Bottom")
		(5 "F.SilkS" user "Ref Des/Silkscreen Top")
		(7 "B.SilkS" user "Ref Des/Silkscreen Bottom")
		(1 "F.Mask" user "Board Geometry/Soldermask Top")
		(3 "B.Mask" user "Board Geometry/Soldermask Bottom")
		(17 "Dwgs.User" user "User.Drawings")
		(19 "Cmts.User" user "User.Comments")
		(21 "Eco1.User" user "User.Eco1")
		(23 "Eco2.User" user "User.Eco2")
		(25 "Edge.Cuts" user "Board Geometry/Outline")
		(27 "Margin" user)
		(31 "F.CrtYd" user "Package Geometry/Place Bound Top")
		(29 "B.CrtYd" user "Package Geometry/Place Bound Bottom")
		(35 "F.Fab" user "Ref Des/Assembly Top")
		(33 "B.Fab" user "Ref Des/Assembly Bottom")
	)
	(footprint ""
		(layer "B.Cu")
		(at 79.550768 -125.8824 -90)
		(property "Reference" "C8M9"
			(at 1.75387 0.874268 0)
			(unlocked yes)
			(layer "B.SilkS")
			(effects
				(font
					(size 0.7874 0.5842)
					(thickness 0.1524)
				)
				(justify mirror)
			)
		)
		(property "Value" ""
			(at 0 0 90)
			(layer "B.Fab")
			(effects
				(font
					(size 1.27 1.27)
				)
				(justify mirror)
			)
		)
		(duplicate_pad_numbers_are_jumpers no)
		(fp_rect
			(start 0.500126 1.598422)
			(end -0.500126 -0.201422)
			(stroke
				(width 0)
				(type default)
			)
			(fill no)
			(layer "B.CrtYd")
		)
		(fp_line
			(start -0.500126 1.598422)
			(end 0.500126 1.598422)
			(stroke
				(width 0.1)
				(type default)
			)
			(layer "B.Fab")
		)
		(fp_line
			(start 0.500126 1.598422)
			(end 0.500126 -0.201422)
			(stroke
				(width 0.1)
				(type default)
			)
			(layer "B.Fab")
		)
		(fp_line
			(start -0.500126 -0.201422)
			(end -0.500126 1.598422)
			(stroke
				(width 0.1)
				(type default)
			)
			(layer "B.Fab")
		)
		(fp_line
			(start 0.500126 -0.201422)
			(end -0.500126 -0.201422)
			(stroke
				(width 0.1)
				(type default)
			)
			(layer "B.Fab")
		)
		(pad "1" smd rect
			(at 0 0 180)
			(size 0.889 0.9906)
			(layers "B.Cu" "B.Mask" "B.Paste")
			(net "PVDDQ_KLM")
		)
		(pad "2" smd rect
			(at 0 1.397 180)
			(size 0.889 0.9906)
			(layers "B.Cu" "B.Mask" "B.Paste")
			(net "GND")
		)
		(zone
			(layer "B.Cu")
			(hatch none 0.5)
			(connect_pads
				(clearance 0)
			)
			(min_thickness 0.25)
			(keepout
				(tracks not_allowed)
				(vias allowed)
				(pads allowed)
				(copperpour not_allowed)
				(footprints allowed)
			)
			(placement
				(enabled no)
				(sheetname "")
			)
			(fill
				(thermal_gap 0.5)
				(thermal_bridge_width 0.5)
				(island_removal_mode 0)
			)
			(polygon
				(pts
					(xy 78.598268 -125.3871) (xy 79.106268 -125.3871) (xy 79.106268 -126.3777) (xy 78.598268 -126.3777)
				)
			)
		)
		(zone
			(layer "B.Cu")
			(hatch none 0.5)
			(connect_pads
				(clearance 0)
			)
			(min_thickness 0.25)
			(keepout
				(tracks allowed)
				(vias not_allowed)
				(pads allowed)
				(copperpour not_allowed)
				(footprints allowed)
			)
			(placement
				(enabled no)
				(sheetname "")
			)
			(fill
				(thermal_gap 0.5)
				(thermal_bridge_width 0.5)
				(island_removal_mode 0)
			)
			(polygon
				(pts
					(xy 78.598268 -125.3871) (xy 79.106268 -125.3871) (xy 79.106268 -126.3777) (xy 78.598268 -126.3777)
				)
			)
		)
	)
	(footprint ""
		(layer "B.Cu")
		(at 348.615 -146.343624 -90)
		(property "Reference" "C3L4"
			(at 0 0 90)
			(layer "B.SilkS")
			(hide yes)
			(effects
				(font
					(size 1.27 1.27)
				)
				(justify mirror)
			)
		)
		(property "Value" ""
			(at 0 0 90)
			(layer "B.Fab")
			(effects
				(font
					(size 1.27 1.27)
				)
				(justify mirror)
			)
		)
		(duplicate_pad_numbers_are_jumpers no)
		(fp_poly
			(pts
				(xy 0.7239 -0.2159) (xy -0.7239 -0.2159) (xy -0.7239 1.9939) (xy 0.7239 1.9939)
			)
			(stroke
				(width 0)
				(type default)
			)
			(fill no)
			(layer "B.CrtYd")
		)
		(fp_line
			(start -0.7239 1.9939)
			(end -0.7239 -0.2159)
			(stroke
				(width 0.1)
				(type default)
			)
			(layer "B.Fab")
		)
		(fp_line
			(start 0.7239 1.9939)
			(end -0.7239 1.9939)
			(stroke
				(width 0.1)
				(type default)
			)
			(layer "B.Fab")
		)
		(fp_line
			(start -0.7239 -0.2159)
			(end 0.7239 -0.2159)
			(stroke
				(width 0.1)
				(type default)
			)
			(layer "B.Fab")
		)
		(fp_line
			(start 0.7239 -0.2159)
			(end 0.7239 1.9939)
			(stroke
				(width 0.1)
				(type default)
			)
			(layer "B.Fab")
		)
		(pad "1" smd rect
			(at 0 0 90)
			(size 1.27 1.016)
			(layers "B.Cu" "B.Mask" "B.Paste")
			(net "VR_FET_SW_P12V_STBY_PVDDQ_DEF")
		)
		(pad "2" smd rect
			(at 0 1.778 90)
			(size 1.27 1.016)
			(layers "B.Cu" "B.Mask" "B.Paste")
			(net "GND")
		)
		(zone
			(layer "B.Cu")
			(hatch none 0.5)
			(connect_pads
				(clearance 0)
			)
			(min_thickness 0.25)
			(keepout
				(tracks not_allowed)
				(vias allowed)
				(pads allowed)
				(copperpour not_allowed)
				(footprints allowed)
			)
			(placement
				(enabled no)
				(sheetname "")
			)
			(fill
				(thermal_gap 0.5)
				(thermal_bridge_width 0.5)
				(island_removal_mode 0)
			)
			(polygon
				(pts
					(xy 348.107 -145.708624) (xy 348.107 -146.978624) (xy 347.345 -146.978624) (xy 347.345 -145.708624)
				)
			)
		)
	)
	(footprint ""
		(layer "B.Cu")
		(at 185.42 -49.7078 90)
		(property "Reference" "C6R16"
			(at -3.12547 4.191 0)
			(unlocked yes)
			(layer "B.SilkS")
			(effects
				(font
					(size 0.7874 0.5842)
					(thickness 0.1524)
				)
				(justify mirror)
			)
		)
		(property "Value" ""
			(at 0 0 90)
			(layer "B.Fab")
			(effects
				(font
					(size 1.27 1.27)
				)
				(justify mirror)
			)
		)
		(duplicate_pad_numbers_are_jumpers no)
		(fp_line
			(start 2.563114 -1.616456)
			(end 2.563114 1.633728)
			(stroke
				(width 0.1524)
				(type default)
			)
			(layer "B.SilkS")
		)
		(fp_line
			(start 1.6002 -1.616456)
			(end 2.563114 -1.616456)
			(stroke
				(width 0.1524)
				(type default)
			)
			(layer "B.SilkS")
		)
		(fp_line
			(start -1.6002 -1.616456)
			(end -2.504948 -1.616456)
			(stroke
				(width 0.1524)
				(type default)
			)
			(layer "B.SilkS")
		)
		(fp_line
			(start -2.504948 -1.616456)
			(end -2.504948 1.633728)
			(stroke
				(width 0.1524)
				(type default)
			)
			(layer "B.SilkS")
		)
		(fp_line
			(start 2.563114 1.633728)
			(end 1.6002 1.633728)
			(stroke
				(width 0.1524)
				(type default)
			)
			(layer "B.SilkS")
		)
		(fp_line
			(start -2.504948 1.633728)
			(end -1.6002 1.633728)
			(stroke
				(width 0.1524)
				(type default)
			)
			(layer "B.SilkS")
		)
		(fp_line
			(start 2.286 7.366)
			(end 2.286 1.632712)
			(stroke
				(width 0.1524)
				(type default)
			)
			(layer "B.SilkS")
		)
		(fp_line
			(start 2.286 7.366)
			(end 1.60147 7.366)
			(stroke
				(width 0.1524)
				(type default)
			)
			(layer "B.SilkS")
		)
		(fp_line
			(start -2.286 7.366)
			(end -2.286 1.63195)
			(stroke
				(width 0.1524)
				(type default)
			)
			(layer "B.SilkS")
		)
		(fp_line
			(start -2.286 7.366)
			(end -1.600708 7.366)
			(stroke
				(width 0.1524)
				(type default)
			)
			(layer "B.SilkS")
		)
		(fp_rect
			(start 2.286 7.366)
			(end -2.286 -0.254)
			(stroke
				(width 0)
				(type default)
			)
			(fill no)
			(layer "B.CrtYd")
		)
		(fp_line
			(start 2.286 -0.254)
			(end -2.286 -0.254)
			(stroke
				(width 0.1)
				(type default)
			)
			(layer "B.Fab")
		)
		(fp_line
			(start -2.286 -0.254)
			(end -2.286 7.366)
			(stroke
				(width 0.1)
				(type default)
			)
			(layer "B.Fab")
		)
		(fp_line
			(start 2.286 7.366)
			(end 2.286 -0.254)
			(stroke
				(width 0.1)
				(type default)
			)
			(layer "B.Fab")
		)
		(fp_line
			(start -2.286 7.366)
			(end 2.286 7.366)
			(stroke
				(width 0.1)
				(type default)
			)
			(layer "B.Fab")
		)
		(pad "1" smd rect
			(at 0 0 270)
			(size 2.54 3.048)
			(layers "B.Cu" "B.Mask" "B.Paste")
			(net "PVCCMCP_CPU1")
		)
		(pad "2" smd rect
			(at 0 7.112 270)
			(size 2.54 3.048)
			(layers "B.Cu" "B.Mask" "B.Paste")
			(net "GND")
		)
	)
	(footprint ""
		(layer "B.Cu")
		(at 489.445046 -46.665388 90)
		(property "Reference" "R25W131"
			(at 0.8382 -0.67818 90)
			(unlocked yes)
			(layer "B.SilkS")
			(effects
				(font
					(size 0.4064 0.254)
					(thickness 0.1524)
				)
				(justify left mirror)
			)
		)
		(property "Value" ""
			(at 0 0 90)
			(layer "B.Fab")
			(effects
				(font
					(size 1.27 1.27)
				)
				(justify mirror)
			)
		)
		(duplicate_pad_numbers_are_jumpers no)
		(fp_poly
			(pts
				(xy 0.2794 -0.1016) (xy -0.2794 -0.1016) (xy -0.2794 0.9906) (xy 0.2794 0.9906)
			)
			(stroke
				(width 0)
				(type default)
			)
			(fill no)
			(layer "B.CrtYd")
		)
		(fp_line
			(start 0.2794 -0.1016)
			(end 0.2794 0.9906)
			(stroke
				(width 0.1)
				(type default)
			)
			(layer "B.Fab")
		)
		(fp_line
			(start -0.2794 -0.1016)
			(end 0.2794 -0.1016)
			(stroke
				(width 0.1)
				(type default)
			)
			(layer "B.Fab")
		)
		(fp_line
			(start 0.2794 0.9906)
			(end -0.2794 0.9906)
			(stroke
				(width 0.1)
				(type default)
			)
			(layer "B.Fab")
		)
		(fp_line
			(start -0.2794 0.9906)
			(end -0.2794 -0.1016)
			(stroke
				(width 0.1)
				(type default)
			)
			(layer "B.Fab")
		)
		(pad "1" smd rect
			(at 0 0 270)
			(size 0.508 0.508)
			(layers "B.Cu" "B.Mask" "B.Paste")
			(net "P3V3")
		)
		(pad "2" smd rect
			(at 0 0.889 270)
			(size 0.508 0.508)
			(layers "B.Cu" "B.Mask" "B.Paste")
			(net "Q25W1_GATE")
		)
		(zone
			(layer "B.Cu")
			(hatch none 0.5)
			(connect_pads
				(clearance 0)
			)
			(min_thickness 0.25)
			(keepout
				(tracks allowed)
				(vias not_allowed)
				(pads allowed)
				(copperpour not_allowed)
				(footprints allowed)
			)
			(placement
				(enabled no)
				(sheetname "")
			)
			(fill
				(thermal_gap 0.5)
				(thermal_bridge_width 0.5)
				(island_removal_mode 0)
			)
			(polygon
				(pts
					(xy 489.699046 -46.919388) (xy 489.699046 -46.411388) (xy 490.080046 -46.411388) (xy 490.080046 -46.919388)
				)
			)
		)
		(zone
			(layer "B.Cu")
			(hatch none 0.5)
			(connect_pads
				(clearance 0)
			)
			(min_thickness 0.25)
			(keepout
				(tracks not_allowed)
				(vias allowed)
				(pads allowed)
				(copperpour not_allowed)
				(footprints allowed)
			)
			(placement
				(enabled no)
				(sheetname "")
			)
			(fill
				(thermal_gap 0.5)
				(thermal_bridge_width 0.5)
				(island_removal_mode 0)
			)
			(polygon
				(pts
					(xy 490.080046 -46.919388) (xy 490.080046 -46.411388) (xy 489.699046 -46.411388) (xy 489.699046 -46.919388)
				)
			)
		)
	)
	(footprint ""
		(layer "B.Cu")
		(at 334.01 2.032 90)
		(property "Reference" "C3U8"
			(at -3.07467 4.318 0)
			(unlocked yes)
			(layer "B.SilkS")
			(effects
				(font
					(size 0.7874 0.5842)
					(thickness 0.1524)
				)
				(justify mirror)
			)
		)
		(property "Value" ""
			(at 0 0 90)
			(layer "B.Fab")
			(effects
				(font
					(size 1.27 1.27)
				)
				(justify mirror)
			)
		)
		(duplicate_pad_numbers_are_jumpers no)
		(fp_line
			(start 2.563114 -1.616456)
			(end 2.563114 1.633728)
			(stroke
				(width 0.1524)
				(type default)
			)
			(layer "B.SilkS")
		)
		(fp_line
			(start 1.6002 -1.616456)
			(end 2.563114 -1.616456)
			(stroke
				(width 0.1524)
				(type default)
			)
			(layer "B.SilkS")
		)
		(fp_line
			(start -1.6002 -1.616456)
			(end -2.504948 -1.616456)
			(stroke
				(width 0.1524)
				(type default)
			)
			(layer "B.SilkS")
		)
		(fp_line
			(start -2.504948 -1.616456)
			(end -2.504948 1.633728)
			(stroke
				(width 0.1524)
				(type default)
			)
			(layer "B.SilkS")
		)
		(fp_line
			(start 2.563114 1.633728)
			(end 1.6002 1.633728)
			(stroke
				(width 0.1524)
				(type default)
			)
			(layer "B.SilkS")
		)
		(fp_line
			(start -2.504948 1.633728)
			(end -1.6002 1.633728)
			(stroke
				(width 0.1524)
				(type default)
			)
			(layer "B.SilkS")
		)
		(fp_line
			(start 2.286 7.366)
			(end 2.286 1.632712)
			(stroke
				(width 0.1524)
				(type default)
			)
			(layer "B.SilkS")
		)
		(fp_line
			(start 2.286 7.366)
			(end 1.60147 7.366)
			(stroke
				(width 0.1524)
				(type default)
			)
			(layer "B.SilkS")
		)
		(fp_line
			(start -2.286 7.366)
			(end -2.286 1.63195)
			(stroke
				(width 0.1524)
				(type default)
			)
			(layer "B.SilkS")
		)
		(fp_line
			(start -2.286 7.366)
			(end -1.600708 7.366)
			(stroke
				(width 0.1524)
				(type default)
			)
			(layer "B.SilkS")
		)
		(fp_rect
			(start -2.286 -0.254)
			(end 2.286 7.366)
			(stroke
				(width 0)
				(type default)
			)
			(fill no)
			(layer "B.CrtYd")
		)
		(fp_line
			(start 2.286 -0.254)
			(end -2.286 -0.254)
			(stroke
				(width 0.1)
				(type default)
			)
			(layer "B.Fab")
		)
		(fp_line
			(start -2.286 -0.254)
			(end -2.286 7.366)
			(stroke
				(width 0.1)
				(type default)
			)
			(layer "B.Fab")
		)
		(fp_line
			(start 2.286 7.366)
			(end 2.286 -0.254)
			(stroke
				(width 0.1)
				(type default)
			)
			(layer "B.Fab")
		)
		(fp_line
			(start -2.286 7.366)
			(end 2.286 7.366)
			(stroke
				(width 0.1)
				(type default)
			)
			(layer "B.Fab")
		)
		(pad "1" smd rect
			(at 0 0 270)
			(size 2.54 3.048)
			(layers "B.Cu" "B.Mask" "B.Paste")
			(net "PVDDQ_ABC")
		)
		(pad "2" smd rect
			(at 0 7.112 270)
			(size 2.54 3.048)
			(layers "B.Cu" "B.Mask" "B.Paste")
			(net "GND")
		)
	)
	(footprint ""
		(layer "B.Cu")
		(at 166.3192 1.2192 90)
		(property "Reference" "C4G22"
			(at 0 0 90)
			(layer "B.SilkS")
			(hide yes)
			(effects
				(font
					(size 1.27 1.27)
				)
				(justify mirror)
			)
		)
		(property "Value" ""
			(at 0 0 90)
			(layer "B.Fab")
			(effects
				(font
					(size 1.27 1.27)
				)
				(justify mirror)
			)
		)
		(duplicate_pad_numbers_are_jumpers no)
		(fp_poly
			(pts
				(xy -0.3048 -0.1016) (xy -0.3048 0.9906) (xy 0.3048 0.9906) (xy 0.3048 -0.1016)
			)
			(stroke
				(width 0)
				(type default)
			)
			(fill no)
			(layer "B.CrtYd")
		)
		(fp_line
			(start 0.3048 -0.1016)
			(end 0.3048 0.9906)
			(stroke
				(width 0.1)
				(type default)
			)
			(layer "B.Fab")
		)
		(fp_line
			(start -0.3048 -0.1016)
			(end 0.3048 -0.1016)
			(stroke
				(width 0.1)
				(type default)
			)
			(layer "B.Fab")
		)
		(fp_line
			(start 0.3048 0.9906)
			(end -0.3048 0.9906)
			(stroke
				(width 0.1)
				(type default)
			)
			(layer "B.Fab")
		)
		(fp_line
			(start -0.3048 0.9906)
			(end -0.3048 -0.1016)
			(stroke
				(width 0.1)
				(type default)
			)
			(layer "B.Fab")
		)
		(pad "1" smd rect
			(at 0 0 270)
			(size 0.508 0.508)
			(layers "B.Cu" "B.Mask" "B.Paste")
			(net "PVCCIO_CPU1")
		)
		(pad "2" smd rect
			(at 0 0.889 270)
			(size 0.508 0.508)
			(layers "B.Cu" "B.Mask" "B.Paste")
			(net "GND")
		)
		(zone
			(layer "B.Cu")
			(hatch none 0.5)
			(connect_pads
				(clearance 0)
			)
			(min_thickness 0.25)
			(keepout
				(tracks allowed)
				(vias not_allowed)
				(pads allowed)
				(copperpour not_allowed)
				(footprints allowed)
			)
			(placement
				(enabled no)
				(sheetname "")
			)
			(fill
				(thermal_gap 0.5)
				(thermal_bridge_width 0.5)
				(island_removal_mode 0)
			)
			(polygon
				(pts
					(xy 166.5732 0.9652) (xy 166.5732 1.4732) (xy 166.9542 1.4732) (xy 166.9542 0.9652)
				)
			)
		)
		(zone
			(layer "B.Cu")
			(hatch none 0.5)
			(connect_pads
				(clearance 0)
			)
			(min_thickness 0.25)
			(keepout
				(tracks not_allowed)
				(vias allowed)
				(pads allowed)
				(copperpour not_allowed)
				(footprints allowed)
			)
			(placement
				(enabled no)
				(sheetname "")
			)
			(fill
				(thermal_gap 0.5)
				(thermal_bridge_width 0.5)
				(island_removal_mode 0)
			)
			(polygon
				(pts
					(xy 166.9542 0.9652) (xy 166.9542 1.4732) (xy 166.5732 1.4732) (xy 166.5732 0.9652)
				)
			)
		)
	)
	(footprint ""
		(layer "B.Cu")
		(at 491.078266 -20.00758 -90)
		(property "Reference" "U9E1"
			(at -4.7498 -1.51257 90)
			(unlocked yes)
			(layer "B.SilkS")
			(effects
				(font
					(size 0.7874 0.5842)
					(thickness 0.1524)
				)
				(justify left mirror)
			)
		)
		(property "Value" ""
			(at 0 0 90)
			(layer "B.Fab")
			(effects
				(font
					(size 1.27 1.27)
				)
				(justify mirror)
			)
		)
		(duplicate_pad_numbers_are_jumpers no)
		(fp_line
			(start -4.826 4.6355)
			(end -1.905 4.6355)
			(stroke
				(width 0.1524)
				(type default)
			)
			(layer "B.SilkS")
		)
		(fp_line
			(start -1.905 4.6355)
			(end -1.905 -0.8255)
			(stroke
				(width 0.1524)
				(type default)
			)
			(layer "B.SilkS")
		)
		(fp_line
			(start -4.0132 0.6731)
			(end -4.0132 -0.8255)
			(stroke
				(width 0.1524)
				(type default)
			)
			(layer "B.SilkS")
		)
		(fp_line
			(start -2.7432 0.6731)
			(end -4.0132 0.6731)
			(stroke
				(width 0.1524)
				(type default)
			)
			(layer "B.SilkS")
		)
		(fp_line
			(start -4.826 -0.8255)
			(end -4.826 4.6355)
			(stroke
				(width 0.1524)
				(type default)
			)
			(layer "B.SilkS")
		)
		(fp_line
			(start -2.7432 -0.8255)
			(end -2.7432 0.6731)
			(stroke
				(width 0.1524)
				(type default)
			)
			(layer "B.SilkS")
		)
		(fp_line
			(start -1.905 -0.8255)
			(end -4.826 -0.8255)
			(stroke
				(width 0.1524)
				(type default)
			)
			(layer "B.SilkS")
		)
		(fp_circle
			(center 1.016 -1.27)
			(end 1.016 -1.4605)
			(stroke
				(width 0.381)
				(type default)
			)
			(fill no)
			(layer "B.SilkS")
		)
		(fp_poly
			(pts
				(xy -6.0833 -0.8255) (xy -6.0833 4.6355) (xy -0.6731 4.6355) (xy -0.6731 -0.8255)
			)
			(stroke
				(width 0)
				(type default)
			)
			(fill no)
			(layer "B.CrtYd")
		)
		(fp_line
			(start -4.0132 0.6731)
			(end -4.0132 -0.8255)
			(stroke
				(width 0.1)
				(type default)
			)
			(layer "B.Fab")
		)
		(fp_line
			(start -2.7432 0.6731)
			(end -4.0132 0.6731)
			(stroke
				(width 0.1)
				(type default)
			)
			(layer "B.Fab")
		)
		(fp_line
			(start -2.7432 -0.8255)
			(end -2.7432 0.6731)
			(stroke
				(width 0.1)
				(type default)
			)
			(layer "B.Fab")
		)
		(fp_rect
			(start -0.6731 4.6355)
			(end -6.0833 -0.8255)
			(stroke
				(width 0)
				(type default)
			)
			(fill no)
			(layer "B.Fab")
		)
		(fp_circle
			(center 1.016 -1.27)
			(end 1.016 -1.4605)
			(stroke
				(width 0.381)
				(type default)
			)
			(fill no)
			(layer "B.Fab")
		)
		(pad "1" smd rect
			(at 0 0 90)
			(size 1.9304 0.635)
			(layers "B.Cu" "B.Mask" "B.Paste")
			(net "SPI_NIC_CS_N")
		)
		(pad "2" smd rect
			(at 0 1.27 90)
			(size 1.9304 0.635)
			(layers "B.Cu" "B.Mask" "B.Paste")
			(net "SPI_NIC_MISO_R")
		)
		(pad "3" smd rect
			(at 0 2.54 90)
			(size 1.9304 0.635)
			(layers "B.Cu" "B.Mask" "B.Paste")
			(net "PU_NV_WP_N")
		)
		(pad "4" smd rect
			(at 0 3.81 90)
			(size 1.9304 0.635)
			(layers "B.Cu" "B.Mask" "B.Paste")
			(net "GND")
		)
		(pad "5" smd rect
			(at -6.7564 3.81 90)
			(size 1.9304 0.635)
			(layers "B.Cu" "B.Mask" "B.Paste")
			(net "SPI_NIC_MOSI")
		)
		(pad "6" smd rect
			(at -6.7564 2.54 90)
			(size 1.9304 0.635)
			(layers "B.Cu" "B.Mask" "B.Paste")
			(net "SPI_NIC_SCLK")
		)
		(pad "7" smd rect
			(at -6.7564 1.27 90)
			(size 1.9304 0.635)
			(layers "B.Cu" "B.Mask" "B.Paste")
			(net "PU_NV_HOLD_N")
		)
		(pad "8" smd rect
			(at -6.7564 0 90)
			(size 1.9304 0.635)
			(layers "B.Cu" "B.Mask" "B.Paste")
			(net "P3V3_STBY")
		)
	)
)
